(kicad_pcb
	(version 20260206)
	(generator "pcbnew")
	(generator_version "10.0")
	(general
		(thickness 1.6)
		(legacy_teardrops no)
	)
	(paper "A4")
	(title_block
		(title "12092022_DA0F0TMDCD0_F0T_Management_Board_D_brd_V3_OCP.brd")
		(comment 1 "Grand Teton / footprints 431-436 of 1440")
	)
	(layers
		(0 "F.Cu" signal "TOP")
		(4 "In1.Cu" signal "GND")
		(6 "In2.Cu" signal "IN1")
		(8 "In3.Cu" signal "GND1")
		(10 "In4.Cu" signal "IN2")
		(12 "In5.Cu" signal "VCC")
		(14 "In6.Cu" signal "VCC1")
		(16 "In7.Cu" signal "IN3")
		(18 "In8.Cu" signal "GND2")
		(20 "In9.Cu" signal "IN4")
		(22 "In10.Cu" signal "GND3")
		(2 "B.Cu" signal "BOTTOM")
		(9 "F.Adhes" user "F.Adhesive")
		(11 "B.Adhes" user "B.Adhesive")
		(13 "F.Paste" user "Package Geometry/Pastemask Top")
		(15 "B.Paste" user "Package Geometry/Pastemask Bottom")
		(5 "F.SilkS" user "Ref Des/Silkscreen Top")
		(7 "B.SilkS" user "Ref Des/Silkscreen Bottom")
		(1 "F.Mask" user "Board Geometry/Soldermask Top")
		(3 "B.Mask" user "Board Geometry/Soldermask Bottom")
		(17 "Dwgs.User" user "User.Drawings")
		(19 "Cmts.User" user "User.Comments")
		(21 "Eco1.User" user "User.Eco1")
		(23 "Eco2.User" user "User.Eco2")
		(25 "Edge.Cuts" user "Board Geometry/Outline")
		(27 "Margin" user)
		(31 "F.CrtYd" user "Package Geometry/Place Bound Top")
		(29 "B.CrtYd" user "Package Geometry/Place Bound Bottom")
		(35 "F.Fab" user "Ref Des/Assembly Top")
		(33 "B.Fab" user "Ref Des/Assembly Bottom")
	)
	(footprint ""
		(layer "F.Cu")
		(at 11.4554 -62.2046 180)
		(property "Reference" "R871"
			(at 0 0 180)
			(layer "F.SilkS")
			(hide yes)
			(effects
				(font
					(size 1.27 1.27)
				)
			)
		)
		(property "Value" ""
			(at 0 0 180)
			(layer "F.Fab")
			(effects
				(font
					(size 1.27 1.27)
				)
			)
		)
		(duplicate_pad_numbers_are_jumpers no)
		(fp_line
			(start 0.7874 0.4064)
			(end -0.7874 0.4064)
			(stroke
				(width 0.1524)
				(type default)
			)
			(layer "F.SilkS")
		)
		(fp_line
			(start 0.7874 -0.4064)
			(end 0.7874 0.4064)
			(stroke
				(width 0.1524)
				(type default)
			)
			(layer "F.SilkS")
		)
		(fp_line
			(start -0.7874 0.4064)
			(end -0.7874 -0.4064)
			(stroke
				(width 0.1524)
				(type default)
			)
			(layer "F.SilkS")
		)
		(fp_line
			(start -0.7874 -0.4064)
			(end 0.7874 -0.4064)
			(stroke
				(width 0.1524)
				(type default)
			)
			(layer "F.SilkS")
		)
		(fp_line
			(start 0.67945 0.3048)
			(end 0.120396 0.3048)
			(stroke
				(width 0.1)
				(type default)
			)
			(layer "F.Fab")
		)
		(fp_line
			(start 0.67945 -0.3048)
			(end 0.67945 0.3048)
			(stroke
				(width 0.1)
				(type default)
			)
			(layer "F.Fab")
		)
		(fp_line
			(start 0.12065 -0.2794)
			(end 0.12065 -0.3048)
			(stroke
				(width 0.1)
				(type default)
			)
			(layer "F.Fab")
		)
		(fp_line
			(start 0.12065 -0.3048)
			(end 0.67945 -0.3048)
			(stroke
				(width 0.1)
				(type default)
			)
			(layer "F.Fab")
		)
		(fp_line
			(start 0.120396 0.3048)
			(end 0.120396 0.2794)
			(stroke
				(width 0.1)
				(type default)
			)
			(layer "F.Fab")
		)
		(fp_line
			(start 0.120396 0.2794)
			(end -0.12065 0.2794)
			(stroke
				(width 0.1)
				(type default)
			)
			(layer "F.Fab")
		)
		(fp_line
			(start -0.12065 0.3048)
			(end -0.67945 0.3048)
			(stroke
				(width 0.1)
				(type default)
			)
			(layer "F.Fab")
		)
		(fp_line
			(start -0.12065 0.2794)
			(end -0.12065 0.3048)
			(stroke
				(width 0.1)
				(type default)
			)
			(layer "F.Fab")
		)
		(fp_line
			(start -0.12065 -0.2794)
			(end 0.12065 -0.2794)
			(stroke
				(width 0.1)
				(type default)
			)
			(layer "F.Fab")
		)
		(fp_line
			(start -0.12065 -0.305054)
			(end -0.12065 -0.2794)
			(stroke
				(width 0.1)
				(type default)
			)
			(layer "F.Fab")
		)
		(fp_line
			(start -0.67945 0.3048)
			(end -0.67945 -0.305054)
			(stroke
				(width 0.1)
				(type default)
			)
			(layer "F.Fab")
		)
		(fp_line
			(start -0.67945 -0.305054)
			(end -0.12065 -0.305054)
			(stroke
				(width 0.1)
				(type default)
			)
			(layer "F.Fab")
		)
		(pad "1" smd circle
			(at -0.40005 0 180)
			(size 0 0)
			(layers "F.Cu" "F.Mask" "F.Paste")
			(net "EN_P3V3_R1")
		)
		(pad "2" smd circle
			(at 0.40005 0 180)
			(size 0 0)
			(layers "F.Cu" "F.Mask" "F.Paste")
			(net "PWRGD_EN_P3V3_R")
		)
	)
	(footprint ""
		(layer "F.Cu")
		(at 63.62827 -63.919862 -90)
		(property "Reference" "R119"
			(at 0 0 270)
			(layer "F.SilkS")
			(hide yes)
			(effects
				(font
					(size 1.27 1.27)
				)
			)
		)
		(property "Value" ""
			(at 0 0 270)
			(layer "F.Fab")
			(effects
				(font
					(size 1.27 1.27)
				)
			)
		)
		(duplicate_pad_numbers_are_jumpers no)
		(fp_line
			(start -0.7874 0.4064)
			(end -0.7874 -0.4064)
			(stroke
				(width 0.1524)
				(type default)
			)
			(layer "F.SilkS")
		)
		(fp_line
			(start 0.7874 0.4064)
			(end -0.7874 0.4064)
			(stroke
				(width 0.1524)
				(type default)
			)
			(layer "F.SilkS")
		)
		(fp_line
			(start -0.7874 -0.4064)
			(end 0.7874 -0.4064)
			(stroke
				(width 0.1524)
				(type default)
			)
			(layer "F.SilkS")
		)
		(fp_line
			(start 0.7874 -0.4064)
			(end 0.7874 0.4064)
			(stroke
				(width 0.1524)
				(type default)
			)
			(layer "F.SilkS")
		)
		(fp_line
			(start -0.67945 0.3048)
			(end -0.67945 -0.305054)
			(stroke
				(width 0.1)
				(type default)
			)
			(layer "F.Fab")
		)
		(fp_line
			(start -0.12065 0.3048)
			(end -0.67945 0.3048)
			(stroke
				(width 0.1)
				(type default)
			)
			(layer "F.Fab")
		)
		(fp_line
			(start 0.120396 0.3048)
			(end 0.120396 0.2794)
			(stroke
				(width 0.1)
				(type default)
			)
			(layer "F.Fab")
		)
		(fp_line
			(start 0.67945 0.3048)
			(end 0.120396 0.3048)
			(stroke
				(width 0.1)
				(type default)
			)
			(layer "F.Fab")
		)
		(fp_line
			(start -0.12065 0.2794)
			(end -0.12065 0.3048)
			(stroke
				(width 0.1)
				(type default)
			)
			(layer "F.Fab")
		)
		(fp_line
			(start 0.120396 0.2794)
			(end -0.12065 0.2794)
			(stroke
				(width 0.1)
				(type default)
			)
			(layer "F.Fab")
		)
		(fp_line
			(start -0.12065 -0.2794)
			(end 0.12065 -0.2794)
			(stroke
				(width 0.1)
				(type default)
			)
			(layer "F.Fab")
		)
		(fp_line
			(start 0.12065 -0.2794)
			(end 0.12065 -0.3048)
			(stroke
				(width 0.1)
				(type default)
			)
			(layer "F.Fab")
		)
		(fp_line
			(start 0.12065 -0.3048)
			(end 0.67945 -0.3048)
			(stroke
				(width 0.1)
				(type default)
			)
			(layer "F.Fab")
		)
		(fp_line
			(start 0.67945 -0.3048)
			(end 0.67945 0.3048)
			(stroke
				(width 0.1)
				(type default)
			)
			(layer "F.Fab")
		)
		(fp_line
			(start -0.67945 -0.305054)
			(end -0.12065 -0.305054)
			(stroke
				(width 0.1)
				(type default)
			)
			(layer "F.Fab")
		)
		(fp_line
			(start -0.12065 -0.305054)
			(end -0.12065 -0.2794)
			(stroke
				(width 0.1)
				(type default)
			)
			(layer "F.Fab")
		)
		(pad "1" smd circle
			(at -0.40005 0 270)
			(size 0 0)
			(layers "F.Cu" "F.Mask" "F.Paste")
			(net "IRQ_BMC_LPC_SERIRQ_ESPI_GF")
		)
		(pad "2" smd circle
			(at 0.40005 0 270)
			(size 0 0)
			(layers "F.Cu" "F.Mask" "F.Paste")
			(net "IRQ_ESPI_LPC_SERIRQ_ALERT0_N")
		)
	)
	(footprint ""
		(layer "F.Cu")
		(at 58.0644 -30.861 90)
		(property "Reference" "R836"
			(at 0 0 90)
			(layer "F.SilkS")
			(hide yes)
			(effects
				(font
					(size 1.27 1.27)
				)
			)
		)
		(property "Value" ""
			(at 0 0 90)
			(layer "F.Fab")
			(effects
				(font
					(size 1.27 1.27)
				)
			)
		)
		(duplicate_pad_numbers_are_jumpers no)
		(fp_line
			(start 0.7874 -0.4064)
			(end 0.7874 0.4064)
			(stroke
				(width 0.1524)
				(type default)
			)
			(layer "F.SilkS")
		)
		(fp_line
			(start -0.7874 -0.4064)
			(end 0.7874 -0.4064)
			(stroke
				(width 0.1524)
				(type default)
			)
			(layer "F.SilkS")
		)
		(fp_line
			(start 0.7874 0.4064)
			(end -0.7874 0.4064)
			(stroke
				(width 0.1524)
				(type default)
			)
			(layer "F.SilkS")
		)
		(fp_line
			(start -0.7874 0.4064)
			(end -0.7874 -0.4064)
			(stroke
				(width 0.1524)
				(type default)
			)
			(layer "F.SilkS")
		)
		(fp_line
			(start -0.12065 -0.305054)
			(end -0.12065 -0.2794)
			(stroke
				(width 0.1)
				(type default)
			)
			(layer "F.Fab")
		)
		(fp_line
			(start -0.67945 -0.305054)
			(end -0.12065 -0.305054)
			(stroke
				(width 0.1)
				(type default)
			)
			(layer "F.Fab")
		)
		(fp_line
			(start 0.67945 -0.3048)
			(end 0.67945 0.3048)
			(stroke
				(width 0.1)
				(type default)
			)
			(layer "F.Fab")
		)
		(fp_line
			(start 0.12065 -0.3048)
			(end 0.67945 -0.3048)
			(stroke
				(width 0.1)
				(type default)
			)
			(layer "F.Fab")
		)
		(fp_line
			(start 0.12065 -0.2794)
			(end 0.12065 -0.3048)
			(stroke
				(width 0.1)
				(type default)
			)
			(layer "F.Fab")
		)
		(fp_line
			(start -0.12065 -0.2794)
			(end 0.12065 -0.2794)
			(stroke
				(width 0.1)
				(type default)
			)
			(layer "F.Fab")
		)
		(fp_line
			(start 0.120396 0.2794)
			(end -0.12065 0.2794)
			(stroke
				(width 0.1)
				(type default)
			)
			(layer "F.Fab")
		)
		(fp_line
			(start -0.12065 0.2794)
			(end -0.12065 0.3048)
			(stroke
				(width 0.1)
				(type default)
			)
			(layer "F.Fab")
		)
		(fp_line
			(start 0.67945 0.3048)
			(end 0.120396 0.3048)
			(stroke
				(width 0.1)
				(type default)
			)
			(layer "F.Fab")
		)
		(fp_line
			(start 0.120396 0.3048)
			(end 0.120396 0.2794)
			(stroke
				(width 0.1)
				(type default)
			)
			(layer "F.Fab")
		)
		(fp_line
			(start -0.12065 0.3048)
			(end -0.67945 0.3048)
			(stroke
				(width 0.1)
				(type default)
			)
			(layer "F.Fab")
		)
		(fp_line
			(start -0.67945 0.3048)
			(end -0.67945 -0.305054)
			(stroke
				(width 0.1)
				(type default)
			)
			(layer "F.Fab")
		)
		(pad "1" smd circle
			(at -0.40005 0 90)
			(size 0 0)
			(layers "F.Cu" "F.Mask" "F.Paste")
			(net "PWRGD_PSU_AC_PWROK")
		)
		(pad "2" smd circle
			(at 0.40005 0 90)
			(size 0 0)
			(layers "F.Cu" "F.Mask" "F.Paste")
			(net "PWRGD_PSU_AC_PWROK_BMC")
		)
	)
	(footprint ""
		(layer "F.Cu")
		(at 54.483 -23.495 90)
		(property "Reference" "C172"
			(at 0 0 90)
			(layer "F.SilkS")
			(hide yes)
			(effects
				(font
					(size 1.27 1.27)
				)
			)
		)
		(property "Value" ""
			(at 0 0 90)
			(layer "F.Fab")
			(effects
				(font
					(size 1.27 1.27)
				)
			)
		)
		(duplicate_pad_numbers_are_jumpers no)
		(fp_line
			(start 0.7874 -0.4064)
			(end 0.7874 0.4064)
			(stroke
				(width 0.1524)
				(type default)
			)
			(layer "F.SilkS")
		)
		(fp_line
			(start -0.7874 -0.4064)
			(end 0.7874 -0.4064)
			(stroke
				(width 0.1524)
				(type default)
			)
			(layer "F.SilkS")
		)
		(fp_line
			(start 0.7874 0.4064)
			(end -0.7874 0.4064)
			(stroke
				(width 0.1524)
				(type default)
			)
			(layer "F.SilkS")
		)
		(fp_line
			(start -0.7874 0.4064)
			(end -0.7874 -0.4064)
			(stroke
				(width 0.1524)
				(type default)
			)
			(layer "F.SilkS")
		)
		(fp_line
			(start -0.12065 -0.305054)
			(end -0.12065 -0.2794)
			(stroke
				(width 0.1)
				(type default)
			)
			(layer "F.Fab")
		)
		(fp_line
			(start -0.67945 -0.305054)
			(end -0.12065 -0.305054)
			(stroke
				(width 0.1)
				(type default)
			)
			(layer "F.Fab")
		)
		(fp_line
			(start 0.67945 -0.3048)
			(end 0.67945 0.3048)
			(stroke
				(width 0.1)
				(type default)
			)
			(layer "F.Fab")
		)
		(fp_line
			(start 0.12065 -0.3048)
			(end 0.67945 -0.3048)
			(stroke
				(width 0.1)
				(type default)
			)
			(layer "F.Fab")
		)
		(fp_line
			(start 0.12065 -0.2794)
			(end 0.12065 -0.3048)
			(stroke
				(width 0.1)
				(type default)
			)
			(layer "F.Fab")
		)
		(fp_line
			(start -0.12065 -0.2794)
			(end 0.12065 -0.2794)
			(stroke
				(width 0.1)
				(type default)
			)
			(layer "F.Fab")
		)
		(fp_line
			(start 0.120396 0.2794)
			(end -0.12065 0.2794)
			(stroke
				(width 0.1)
				(type default)
			)
			(layer "F.Fab")
		)
		(fp_line
			(start -0.12065 0.2794)
			(end -0.12065 0.3048)
			(stroke
				(width 0.1)
				(type default)
			)
			(layer "F.Fab")
		)
		(fp_line
			(start 0.67945 0.3048)
			(end 0.120396 0.3048)
			(stroke
				(width 0.1)
				(type default)
			)
			(layer "F.Fab")
		)
		(fp_line
			(start 0.120396 0.3048)
			(end 0.120396 0.2794)
			(stroke
				(width 0.1)
				(type default)
			)
			(layer "F.Fab")
		)
		(fp_line
			(start -0.12065 0.3048)
			(end -0.67945 0.3048)
			(stroke
				(width 0.1)
				(type default)
			)
			(layer "F.Fab")
		)
		(fp_line
			(start -0.67945 0.3048)
			(end -0.67945 -0.305054)
			(stroke
				(width 0.1)
				(type default)
			)
			(layer "F.Fab")
		)
		(pad "1" smd circle
			(at -0.40005 0 90)
			(size 0 0)
			(layers "F.Cu" "F.Mask" "F.Paste")
			(net "P5V_AUX")
		)
		(pad "2" smd circle
			(at 0.40005 0 90)
			(size 0 0)
			(layers "F.Cu" "F.Mask" "F.Paste")
			(net "GND")
		)
	)
	(footprint ""
		(layer "F.Cu")
		(at 75.946 -74.422 -90)
		(property "Reference" "R881"
			(at 0 0 270)
			(layer "F.SilkS")
			(hide yes)
			(effects
				(font
					(size 1.27 1.27)
				)
			)
		)
		(property "Value" ""
			(at 0 0 270)
			(layer "F.Fab")
			(effects
				(font
					(size 1.27 1.27)
				)
			)
		)
		(duplicate_pad_numbers_are_jumpers no)
		(fp_line
			(start -0.7874 0.4064)
			(end -0.7874 -0.4064)
			(stroke
				(width 0.1524)
				(type default)
			)
			(layer "F.SilkS")
		)
		(fp_line
			(start 0.7874 0.4064)
			(end -0.7874 0.4064)
			(stroke
				(width 0.1524)
				(type default)
			)
			(layer "F.SilkS")
		)
		(fp_line
			(start -0.7874 -0.4064)
			(end 0.7874 -0.4064)
			(stroke
				(width 0.1524)
				(type default)
			)
			(layer "F.SilkS")
		)
		(fp_line
			(start 0.7874 -0.4064)
			(end 0.7874 0.4064)
			(stroke
				(width 0.1524)
				(type default)
			)
			(layer "F.SilkS")
		)
		(fp_line
			(start -0.67945 0.3048)
			(end -0.67945 -0.305054)
			(stroke
				(width 0.1)
				(type default)
			)
			(layer "F.Fab")
		)
		(fp_line
			(start -0.12065 0.3048)
			(end -0.67945 0.3048)
			(stroke
				(width 0.1)
				(type default)
			)
			(layer "F.Fab")
		)
		(fp_line
			(start 0.120396 0.3048)
			(end 0.120396 0.2794)
			(stroke
				(width 0.1)
				(type default)
			)
			(layer "F.Fab")
		)
		(fp_line
			(start 0.67945 0.3048)
			(end 0.120396 0.3048)
			(stroke
				(width 0.1)
				(type default)
			)
			(layer "F.Fab")
		)
		(fp_line
			(start -0.12065 0.2794)
			(end -0.12065 0.3048)
			(stroke
				(width 0.1)
				(type default)
			)
			(layer "F.Fab")
		)
		(fp_line
			(start 0.120396 0.2794)
			(end -0.12065 0.2794)
			(stroke
				(width 0.1)
				(type default)
			)
			(layer "F.Fab")
		)
		(fp_line
			(start -0.12065 -0.2794)
			(end 0.12065 -0.2794)
			(stroke
				(width 0.1)
				(type default)
			)
			(layer "F.Fab")
		)
		(fp_line
			(start 0.12065 -0.2794)
			(end 0.12065 -0.3048)
			(stroke
				(width 0.1)
				(type default)
			)
			(layer "F.Fab")
		)
		(fp_line
			(start 0.12065 -0.3048)
			(end 0.67945 -0.3048)
			(stroke
				(width 0.1)
				(type default)
			)
			(layer "F.Fab")
		)
		(fp_line
			(start 0.67945 -0.3048)
			(end 0.67945 0.3048)
			(stroke
				(width 0.1)
				(type default)
			)
			(layer "F.Fab")
		)
		(fp_line
			(start -0.67945 -0.305054)
			(end -0.12065 -0.305054)
			(stroke
				(width 0.1)
				(type default)
			)
			(layer "F.Fab")
		)
		(fp_line
			(start -0.12065 -0.305054)
			(end -0.12065 -0.2794)
			(stroke
				(width 0.1)
				(type default)
			)
			(layer "F.Fab")
		)
		(pad "1" smd circle
			(at -0.40005 0 270)
			(size 0 0)
			(layers "F.Cu" "F.Mask" "F.Paste")
			(net "P3V3_AUX")
		)
		(pad "2" smd circle
			(at 0.40005 0 270)
			(size 0 0)
			(layers "F.Cu" "F.Mask" "F.Paste")
			(net "FM_JTAG_TCK_MUX_BMC_SEL_R")
		)
	)
	(footprint ""
		(layer "F.Cu")
		(at 32.766 -10.6426)
		(property "Reference" "Q9"
			(at 1.397 1.65227 0)
			(unlocked yes)
			(layer "F.SilkS")
			(effects
				(font
					(size 0.7874 0.5842)
					(thickness 0.1524)
				)
				(justify left)
			)
		)
		(property "Value" ""
			(at 0 0 0)
			(layer "F.Fab")
			(effects
				(font
					(size 1.27 1.27)
				)
			)
		)
		(duplicate_pad_numbers_are_jumpers no)
		(fp_line
			(start -1.332738 -1.100074)
			(end -0.4826 -1.100074)
			(stroke
				(width 0.1524)
				(type default)
			)
			(layer "F.SilkS")
		)
		(fp_line
			(start -1.332738 1.100074)
			(end -1.332738 -1.100074)
			(stroke
				(width 0.1524)
				(type default)
			)
			(layer "F.SilkS")
		)
		(fp_line
			(start -0.4826 -1.100074)
			(end 0 -0.541274)
			(stroke
				(width 0.1524)
				(type default)
			)
			(layer "F.SilkS")
		)
		(fp_line
			(start 0 -0.541274)
			(end 0.4826 -1.100074)
			(stroke
				(width 0.1524)
				(type default)
			)
			(layer "F.SilkS")
		)
		(fp_line
			(start 0.4826 -1.100074)
			(end 1.332738 -1.100074)
			(stroke
				(width 0.1524)
				(type default)
			)
			(layer "F.SilkS")
		)
		(fp_line
			(start 1.332738 -1.100074)
			(end 1.332738 1.100074)
			(stroke
				(width 0.1524)
				(type default)
			)
			(layer "F.SilkS")
		)
		(fp_line
			(start 1.332738 1.100074)
			(end -1.332738 1.100074)
			(stroke
				(width 0.1524)
				(type default)
			)
			(layer "F.SilkS")
		)
		(fp_poly
			(pts
				(xy -2.169668 -1.389634) (xy -1.673352 -1.88595) (xy -1.425194 -1.141222)
			)
			(stroke
				(width 0)
				(type default)
			)
			(fill yes)
			(layer "F.SilkS")
		)
		(fp_line
			(start -0.674878 -1.100074)
			(end 0.674878 -1.100074)
			(stroke
				(width 0.1)
				(type default)
			)
			(layer "F.Fab")
		)
		(fp_line
			(start -0.674878 1.100074)
			(end -0.674878 -1.100074)
			(stroke
				(width 0.1)
				(type default)
			)
			(layer "F.Fab")
		)
		(fp_line
			(start 0.674878 -1.100074)
			(end 0.674878 1.100074)
			(stroke
				(width 0.1)
				(type default)
			)
			(layer "F.Fab")
		)
		(fp_line
			(start 0.674878 1.100074)
			(end -0.674878 1.100074)
			(stroke
				(width 0.1)
				(type default)
			)
			(layer "F.Fab")
		)
		(fp_poly
			(pts
				(xy -2.2352 -0.298958) (xy -2.2352 -1.001014) (xy -1.533144 -0.649986)
			)
			(stroke
				(width 0)
				(type default)
			)
			(fill yes)
			(layer "F.Fab")
		)
		(pad "1" smd rect
			(at -0.94996 -0.649986 90)
			(size 0.4318 0.508)
			(layers "F.Cu" "F.Mask" "F.Paste")
			(net "GND")
		)
		(pad "2" smd rect
			(at -0.94996 0 90)
			(size 0.4318 0.508)
			(layers "F.Cu" "F.Mask" "F.Paste")
			(net "ID_LED_BUF")
		)
		(pad "3" smd rect
			(at -0.94996 0.649986 90)
			(size 0.4318 0.508)
			(layers "F.Cu" "F.Mask" "F.Paste")
			(net "Net_318")
		)
		(pad "4" smd rect
			(at 0.94996 0.649986 90)
			(size 0.4318 0.508)
			(layers "F.Cu" "F.Mask" "F.Paste")
			(net "Net_320")
		)
		(pad "5" smd rect
			(at 0.94996 0 90)
			(size 0.4318 0.508)
			(layers "F.Cu" "F.Mask" "F.Paste")
			(net "Net_319")
		)
		(pad "6" smd rect
			(at 0.94996 -0.649986 90)
			(size 0.4318 0.508)
			(layers "F.Cu" "F.Mask" "F.Paste")
			(net "ID_LED_D_P3V3_AUX")
		)
	)
)
